FILE_TYPE = MULTI_PHYS_TABLE;
PART 'DIODE'
{=======================================================================================================================================================================================}
:VALUE         | PACK_TYPE | MATERIAL | PART_NUMBER     = EnvComp                  | PART_NUMBER  | JEDEC_TYPE | CLASS | DESCRIPTION                               | HEIGHT    | COMPONENT_TYPE | LEAD_LENGTH | LPID   | SPEED_URL | Status |RPL| AML | Bus_Unit | Days ;
{=======================================================================================================================================================================================}
'1N4148W'      | 'SM'      | 'IC'     | 'D89194-001'(!) = 'YES;YES;UNK;UNK;ok;VLD' | 'D89194-001' | 'SOD123A'  | 'IC'  | '1N4148W'                                 | '0.053 IN' | 'SMALLSMT'     | ''         | ''     | 'http://speed.intel.com:8081/speed/module/pdm/item/pdm_item_detail_direct.asp?item_cde=D89194-001&item_rev=01&url_param=unused' | 'Design' | 'NO' | '1' | 'SMO_IC' | '???' 
'1N4148W'      | 'SM'      | 'EMPTY'  | 'D89194-001'(!) = 'YES;YES;UNK;UNK;ok;VLD' | 'D89194-001' | 'SOD123A'  | 'IO'  | '1N4148W'                                 | '0.053 IN' | 'SMALLSMT'     | ''         | ''     | 'http://speed.intel.com:8081/speed/module/pdm/item/pdm_item_detail_direct.asp?item_cde=D89194-001&item_rev=01&url_param=unused' | 'Design' | 'NO' | '1' | 'SMO_IC' | '???' 
'1N5819HW'     | 'SMLF'    | 'IC'     | 'D55839-001'(!) = 'YES;YES;YES;UNK;ok;VLD' | 'D55839-001' | 'SOD123A'  | 'IC'  | '1N5819HW'                                | '0.053 IN' | 'SMALLSMT'     | ''         | ''     | 'http://speed.intel.com:8081/speed/module/pdm/item/pdm_item_detail_direct.asp?item_cde=D55839-001&item_rev=01&url_param=unused' | 'Conditional' | 'YES' | '1' | 'SMO_IC' | '48' 
'1N5819HW'     | 'SMLF'    | 'EMPTY'  | 'D55839-001'(!) = 'YES;YES;YES;UNK;ok;VLD' | 'D55839-001' | 'SOD123A'  | 'IO'  | '1N5819HW'                                | '0.053 IN' | 'SMALLSMT'     | ''         | ''     | 'http://speed.intel.com:8081/speed/module/pdm/item/pdm_item_detail_direct.asp?item_cde=D55839-001&item_rev=01&url_param=unused' | 'Conditional' | 'YES' | '1' | 'SMO_IC' | '48' 
'BAT54WS'      | 'SMLF'    | 'IC'     | 'C73510-001'(!) = 'YES;YES;YES;UNK;ok;VLD' | 'C73510-001' | 'SOD323A'  | 'IC'  | 'BAT54WS'                                 | '0.042 IN' | 'SMALLSMT'     | ''         | ''     | 'http://speed.intel.com:8081/speed/module/pdm/item/pdm_item_detail_direct.asp?item_cde=C73510-001&item_rev=01&url_param=unused' | 'Conditional' | 'YES' | '1' | 'SMO_IC' | '49' 
'BAT54WS'      | 'SMLF'    | 'EMPTY'  | 'C73510-001'(!) = 'YES;YES;YES;UNK;ok;VLD' | 'C73510-001' | 'SOD323A'  | 'IO'  | 'BAT54WS'                                 | '0.042 IN' | 'SMALLSMT'     | ''         | ''     | 'http://speed.intel.com:8081/speed/module/pdm/item/pdm_item_detail_direct.asp?item_cde=C73510-001&item_rev=01&url_param=unused' | 'Conditional' | 'YES' | '1' | 'SMO_IC' | '49' 
'MBRS340T3G'   | 'SM'      | 'IC'     | 'C81983-002'(!) = 'Y/E;Y/E;YES;UNK;ok;VLD' | 'C81983-002' | 'SCR3125A' | 'IC'  | 'DIO,3.0A,40V,403-03,SHTKY'               | '0.101 IN' | 'SMTOTHER'     | ''         | '472'  | 'http://speed.intel.com:8081/speed/module/pdm/item/pdm_item_detail_direct.asp?item_cde=C81983-002&item_rev=01&url_param=unused' | 'Design' | 'YES' | '2' | 'SMO_IC' | '???' 
'MBRS340T3G'   | 'SM'      | 'EMPTY'  | 'C81983-002'(!) = 'Y/E;Y/E;YES;UNK;ok;VLD' | 'C81983-002' | 'SCR3125A' | 'IO'  | 'DIO,3.0A,40V,403-03,SHTKY'               | '0.101 IN' | 'SMTOTHER'     | ''         | '472'  | 'http://speed.intel.com:8081/speed/module/pdm/item/pdm_item_detail_direct.asp?item_cde=C81983-002&item_rev=01&url_param=unused' | 'Design' | 'YES' | '2' | 'SMO_IC' | '???' 
'SDMK0340L'    | 'SM'      | 'IC'     | 'H71799-001'(!) = ''                       | 'H71799-001' | 'SOD323A'  | 'IC'  | 'IC,DS,DIO,SOD323,SDMK0340,SCHTKY'        | '0.047 IN' | 'SMALLSMT'     | ''         | '789'  | 'http://speed.intel.com:8081/speed/module/pdm/item/pdm_item_detail_direct.asp?item_cde=H71799-001&item_rev=01&url_param=unused' | '' | '' | '' | '' | '' 
'SDMK0340L'    | 'SM'      | 'EMPTY'  | 'H71799-001'(!) = ''                       | 'H71799-001' | 'SOD323A'  | 'IO'  | 'IC,DS,DIO,SOD323,SDMK0340,SCHTKY'        | '0.047 IN' | 'SMALLSMT'     | ''         | '789'  | 'http://speed.intel.com:8081/speed/module/pdm/item/pdm_item_detail_direct.asp?item_cde=H71799-001&item_rev=01&url_param=unused' | '' | '' | '' | '' | '' 
END_PART
END.
